(kicad_pcb
	(version 20241229)
	(generator "pcbnew")
	(generator_version "9.0")
	(general
		(thickness 1.6296)
		(legacy_teardrops no)
	)
	(paper "A3")
	(title_block
		(title "Thunderbolt to 10GbE adapter")
		(date "2026-04-21")
		(rev "1.1.0")
		(company "Antmicro Ltd")
		(comment 1 "www.antmicro.com")
		(comment 9 "footprints 138-140 of 703")
	)
	(layers
		(0 "F.Cu" signal)
		(4 "In1.Cu" signal)
		(6 "In2.Cu" signal)
		(8 "In3.Cu" signal)
		(10 "In4.Cu" signal)
		(12 "In5.Cu" signal)
		(14 "In6.Cu" signal)
		(2 "B.Cu" signal)
		(9 "F.Adhes" user "F.Adhesive")
		(11 "B.Adhes" user "B.Adhesive")
		(13 "F.Paste" user)
		(15 "B.Paste" user)
		(5 "F.SilkS" user "F.Silkscreen")
		(7 "B.SilkS" user "B.Silkscreen")
		(1 "F.Mask" user)
		(3 "B.Mask" user)
		(17 "Dwgs.User" user "User.Drawings")
		(19 "Cmts.User" user "User.Comments")
		(21 "Eco1.User" user "User.Eco1")
		(23 "Eco2.User" user "User.Eco2")
		(25 "Edge.Cuts" user)
		(27 "Margin" user)
		(31 "F.CrtYd" user "F.Courtyard")
		(29 "B.CrtYd" user "B.Courtyard")
		(35 "F.Fab" user)
		(33 "B.Fab" user)
	)
	(footprint "antmicro-footprints:C_0603_1608Metric_EIA"
		(layer "F.Cu")
		(at 144.150001 105.600001 90)
		(descr "Capacitor SMD 0603, IPC-7351 Density Level A")
		(tags "Capacitor 0603")
		(property "Reference" "C143"
			(at -17.849995 15.649999 90)
			(layer "F.SilkS")
			(effects
				(font
					(size 0.7 0.7)
					(thickness 0.15)
				)
			)
		)
		(property "Value" "C_22u_16V_0603"
			(at -1.42757 1.770288 90)
			(layer "F.Fab")
			(effects
				(font
					(size 0.7 0.7)
					(thickness 0.15)
				)
				(justify left bottom)
			)
		)
		(property "Datasheet" "https://product.samsungsem.com/mlcc/CL10A226MO7JZN.do"
			(at 0 0 90)
			(layer "F.Fab")
			(hide yes)
			(effects
				(font
					(size 1.27 1.27)
					(thickness 0.15)
				)
			)
		)
		(property "Description" "SMD Multilayer Ceramic Capacitor"
			(at 0 0 90)
			(layer "F.Fab")
			(hide yes)
			(effects
				(font
					(size 1.27 1.27)
					(thickness 0.15)
				)
			)
		)
		(property "MPN" "CL10A226MO7JZNC"
			(at 0 0 90)
			(unlocked yes)
			(layer "F.Fab")
			(hide yes)
			(effects
				(font
					(size 1 1)
					(thickness 0.15)
				)
			)
		)
		(property "Manufacturer" "Samsung Electro-Mechanics"
			(at 0 0 90)
			(unlocked yes)
			(layer "F.Fab")
			(hide yes)
			(effects
				(font
					(size 1 1)
					(thickness 0.15)
				)
			)
		)
		(property "License" "Apache-2.0"
			(at 0 0 90)
			(unlocked yes)
			(layer "F.Fab")
			(hide yes)
			(effects
				(font
					(size 1 1)
					(thickness 0.15)
				)
			)
		)
		(property "Author" "Antmicro"
			(at 0 0 90)
			(unlocked yes)
			(layer "F.Fab")
			(hide yes)
			(effects
				(font
					(size 1 1)
					(thickness 0.15)
				)
			)
		)
		(property "Val" "22u"
			(at 0 0 90)
			(unlocked yes)
			(layer "F.Fab")
			(hide yes)
			(effects
				(font
					(size 1 1)
					(thickness 0.15)
				)
			)
		)
		(property "Voltage" "16V"
			(at 0 0 90)
			(unlocked yes)
			(layer "F.Fab")
			(hide yes)
			(effects
				(font
					(size 1 1)
					(thickness 0.15)
				)
			)
		)
		(property "Dielectric" ""
			(at 0 0 90)
			(unlocked yes)
			(layer "F.Fab")
			(hide yes)
			(effects
				(font
					(size 1 1)
					(thickness 0.15)
				)
			)
		)
		(sheetname "/X710 DCDC converters/")
		(sheetfile "DCDC_converters_X710.kicad_sch")
		(attr smd)
		(fp_line
			(start -0.15 -0.55)
			(end 0.15 -0.55)
			(stroke
				(width 0.15)
				(type solid)
			)
			(layer "F.SilkS")
		)
		(fp_line
			(start -0.15 0.55)
			(end 0.15 0.55)
			(stroke
				(width 0.15)
				(type solid)
			)
			(layer "F.SilkS")
		)
		(fp_rect
			(start -1.25 -0.65)
			(end 1.25 0.65)
			(stroke
				(width 0.05)
				(type solid)
			)
			(fill no)
			(layer "F.CrtYd")
		)
		(fp_rect
			(start -0.8 -0.45)
			(end 0.8 0.45)
			(stroke
				(width 0.15)
				(type solid)
			)
			(fill no)
			(layer "F.Fab")
		)
		(fp_text user "Author: Antmicro"
			(at -1.682 4.894 90)
			(layer "F.Fab")
			(effects
				(font
					(size 0.7 0.7)
					(thickness 0.15)
				)
				(justify left bottom)
			)
		)
		(fp_text user "License: Apache-2.0"
			(at -1.682 5.895 90)
			(layer "F.Fab")
			(effects
				(font
					(size 0.7 0.7)
					(thickness 0.15)
				)
				(justify left bottom)
			)
		)
		(fp_text user "${REFERENCE}"
			(at -1.682 3.895 90)
			(layer "F.Fab")
			(effects
				(font
					(size 0.7 0.7)
					(thickness 0.15)
				)
				(justify left bottom)
			)
		)
		(pad "1" smd roundrect
			(at -0.7 0 90)
			(size 0.8 1.1)
			(layers "F.Cu" "F.Mask" "F.Paste")
			(roundrect_rratio 0.2)
			(net 23 "GND")
			(pintype "passive")
		)
		(pad "2" smd roundrect
			(at 0.7 0 90)
			(size 0.8 1.1)
			(layers "F.Cu" "F.Mask" "F.Paste")
			(roundrect_rratio 0.2)
			(net 341 "/X710 DCDC converters/+DVDD_OUT")
			(pintype "passive")
		)
	)
	(footprint "antmicro-footprints:C_0402_1005Metric"
		(layer "F.Cu")
		(at 129.4 103.1 180)
		(descr "Capacitor SMD 0402")
		(tags "capacitor SMD 0402")
		(property "Reference" "C40"
			(at 2 0 180)
			(layer "F.SilkS")
			(effects
				(font
					(size 0.7 0.7)
					(thickness 0.15)
				)
			)
		)
		(property "Value" "C_10p_0402"
			(at -1.022927 2.155213 180)
			(layer "F.Fab")
			(effects
				(font
					(size 0.7 0.7)
					(thickness 0.15)
				)
				(justify left bottom)
			)
		)
		(property "Datasheet" "https://www.murata.com/products/productdetail?partno=GCM1555C1H100GA16%23"
			(at 0 0 180)
			(layer "F.Fab")
			(hide yes)
			(effects
				(font
					(size 1.27 1.27)
					(thickness 0.15)
				)
			)
		)
		(property "Description" "SMD Multilayer Ceramic Capacitor, 10 pF, 50 V, 0402 [1005 Metric], ± 2%, C0G / NP0, GCM"
			(at 0 0 180)
			(layer "F.Fab")
			(hide yes)
			(effects
				(font
					(size 1.27 1.27)
					(thickness 0.15)
				)
			)
		)
		(property "MPN" "GCM1555C1H100GA16D"
			(at 0 0 180)
			(unlocked yes)
			(layer "F.Fab")
			(hide yes)
			(effects
				(font
					(size 1 1)
					(thickness 0.15)
				)
			)
		)
		(property "Manufacturer" "Murata"
			(at 0 0 180)
			(unlocked yes)
			(layer "F.Fab")
			(hide yes)
			(effects
				(font
					(size 1 1)
					(thickness 0.15)
				)
			)
		)
		(property "License" "Apache-2.0"
			(at 0 0 180)
			(unlocked yes)
			(layer "F.Fab")
			(hide yes)
			(effects
				(font
					(size 1 1)
					(thickness 0.15)
				)
			)
		)
		(property "Val" "10p"
			(at 0 0 180)
			(unlocked yes)
			(layer "F.Fab")
			(hide yes)
			(effects
				(font
					(size 1 1)
					(thickness 0.15)
				)
			)
		)
		(property "Voltage" "50V"
			(at 0 0 180)
			(unlocked yes)
			(layer "F.Fab")
			(hide yes)
			(effects
				(font
					(size 1 1)
					(thickness 0.15)
				)
			)
		)
		(property "Dielectric" "C0G"
			(at 0 0 180)
			(unlocked yes)
			(layer "F.Fab")
			(hide yes)
			(effects
				(font
					(size 1 1)
					(thickness 0.15)
				)
			)
		)
		(property "Author" "Antmicro"
			(at 0 0 180)
			(unlocked yes)
			(layer "F.Fab")
			(hide yes)
			(effects
				(font
					(size 1 1)
					(thickness 0.15)
				)
			)
		)
		(sheetname "/TB Controller/")
		(sheetfile "tb.kicad_sch")
		(attr smd)
		(fp_rect
			(start -0.925 -0.47)
			(end 0.925 0.47)
			(stroke
				(width 0.05)
				(type default)
			)
			(fill no)
			(layer "F.CrtYd")
		)
		(fp_line
			(start 0.504 0.248)
			(end -0.494 0.248)
			(stroke
				(width 0.15)
				(type solid)
			)
			(layer "F.Fab")
		)
		(fp_line
			(start 0.504 -0.25)
			(end 0.504 0.248)
			(stroke
				(width 0.15)
				(type solid)
			)
			(layer "F.Fab")
		)
		(fp_line
			(start -0.494 0.248)
			(end -0.494 -0.25)
			(stroke
				(width 0.15)
				(type solid)
			)
			(layer "F.Fab")
		)
		(fp_line
			(start -0.494 -0.25)
			(end 0.504 -0.25)
			(stroke
				(width 0.15)
				(type solid)
			)
			(layer "F.Fab")
		)
		(fp_text user "${REFERENCE}"
			(at -0.939 4.599 180)
			(layer "F.Fab")
			(effects
				(font
					(size 0.7 0.7)
					(thickness 0.15)
				)
				(justify left bottom)
			)
		)
		(fp_text user "Author: Antmicro"
			(at -0.939 3.399 180)
			(layer "F.Fab")
			(effects
				(font
					(size 0.7 0.7)
					(thickness 0.15)
				)
				(justify left bottom)
			)
		)
		(fp_text user "License: Apache-2.0"
			(at -0.939 5.799 180)
			(layer "F.Fab")
			(effects
				(font
					(size 0.7 0.7)
					(thickness 0.15)
				)
				(justify left bottom)
			)
		)
		(pad "1" smd roundrect
			(at -0.48 0 180)
			(size 0.59 0.64)
			(layers "F.Cu" "F.Mask" "F.Paste")
			(roundrect_rratio 0.25)
			(net 23 "GND")
			(pintype "passive")
		)
		(pad "2" smd roundrect
			(at 0.48 0 180)
			(size 0.59 0.64)
			(layers "F.Cu" "F.Mask" "F.Paste")
			(roundrect_rratio 0.25)
			(net 401 "Net-(U5-XIN{slash}CLKIN)")
			(pintype "passive")
		)
	)
	(footprint "antmicro-footprints:USB-C_Receptacle_JAE_DX07S024JJ2"
		(layer "F.Cu")
		(at 122.375 151.315)
		(property "Reference" "J1"
			(at 1.825 -5.315 0)
			(layer "F.SilkS")
			(effects
				(font
					(size 0.7 0.7)
					(thickness 0.15)
				)
				(justify left bottom)
			)
		)
		(property "Value" "USB-C_JAE_DX07S024JJ2"
			(at -5 5.6 0)
			(layer "F.Fab")
			(effects
				(font
					(size 0.7 0.7)
					(thickness 0.15)
				)
				(justify left bottom)
			)
		)
		(property "Datasheet" "https://www.jae.com/en/connectors/series/detail/product/id=66508"
			(at 0 0 0)
			(layer "F.Fab")
			(hide yes)
			(effects
				(font
					(size 1.27 1.27)
					(thickness 0.15)
				)
			)
		)
		(property "Description" "USB-C (USB TYPE-C) USB 3.2 Gen 2 (USB 3.1 Gen 2, Superspeed + (USB 3.1)) Receptacle Connector 24 Position Surface Mount, Right Angle"
			(at 0 0 0)
			(layer "F.Fab")
			(hide yes)
			(effects
				(font
					(size 1.27 1.27)
					(thickness 0.15)
				)
			)
		)
		(property "MPN" "DX07S024JJ2"
			(at 0 0 0)
			(unlocked yes)
			(layer "F.Fab")
			(hide yes)
			(effects
				(font
					(size 1 1)
					(thickness 0.15)
				)
			)
		)
		(property "Manufacturer" "JAE Electronics"
			(at 0 0 0)
			(unlocked yes)
			(layer "F.Fab")
			(hide yes)
			(effects
				(font
					(size 1 1)
					(thickness 0.15)
				)
			)
		)
		(property "Author" "Antmicro"
			(at 0 0 0)
			(unlocked yes)
			(layer "F.Fab")
			(hide yes)
			(effects
				(font
					(size 1 1)
					(thickness 0.15)
				)
			)
		)
		(property "License" "Apache-2.0"
			(at 0 0 0)
			(unlocked yes)
			(layer "F.Fab")
			(hide yes)
			(effects
				(font
					(size 1 1)
					(thickness 0.15)
				)
			)
		)
		(sheetname "/USB-C connector/")
		(sheetfile "USB-C_connector.kicad_sch")
		(attr smd)
		(fp_line
			(start -4.47 -1.645)
			(end -4.47 0.313)
			(stroke
				(width 0.15)
				(type solid)
			)
			(layer "F.SilkS")
		)
		(fp_line
			(start 4.469 -1.645)
			(end 4.469 0.313)
			(stroke
				(width 0.15)
				(type solid)
			)
			(layer "F.SilkS")
		)
		(fp_circle
			(center -2.625 -4.885)
			(end -2.576 -4.885)
			(stroke
				(width 0.15)
				(type solid)
			)
			(fill yes)
			(layer "F.SilkS")
		)
		(fp_rect
			(start -5.571 -4.885)
			(end 5.669 4.584)
			(stroke
				(width 0.05)
				(type solid)
			)
			(fill no)
			(layer "F.CrtYd")
		)
		(fp_line
			(start -4.96 -4.4)
			(end -4.81 -4.55)
			(stroke
				(width 0.15)
				(type solid)
			)
			(layer "F.Fab")
		)
		(fp_rect
			(start -4.971 -4.575)
			(end 4.969 4.084)
			(stroke
				(width 0.15)
				(type solid)
			)
			(fill no)
			(layer "F.Fab")
		)
		(fp_text user "Author: Antmicro"
			(at -5.571 7.6 0)
			(layer "F.Fab")
			(effects
				(font
					(size 0.7 0.7)
					(thickness 0.15)
				)
				(justify left bottom)
			)
		)
		(fp_text user "License: Apache-2.0"
			(at -5.571 8.8 0)
			(layer "F.Fab")
			(effects
				(font
					(size 0.7 0.7)
					(thickness 0.15)
				)
				(justify left bottom)
			)
		)
		(fp_text user "${REFERENCE}"
			(at -5.571 10 0)
			(layer "F.Fab")
			(effects
				(font
					(size 0.7 0.7)
					(thickness 0.15)
				)
				(justify left bottom)
			)
		)
		(pad "" np_thru_hole circle
			(at -3.601 -1.115)
			(size 0.63 0.63)
			(drill 0.63)
			(layers "*.Cu" "*.Mask")
		)
		(pad "" np_thru_hole oval
			(at 3.6 -1.18)
			(size 0.88 0.53)
			(drill oval 0.88 0.53)
			(layers "*.Cu" "*.Mask")
		)
		(pad "A1" smd rect
			(at -2.625 -3.817)
			(size 0.27 0.9)
			(layers "F.Cu" "F.Mask" "F.Paste")
			(net 23 "GND")
			(pinfunction "GND")
			(pintype "power_in")
		)
		(pad "A2" smd rect
			(at -2.125 -3.817)
			(size 0.27 0.9)
			(layers "F.Cu" "F.Mask" "F.Paste")
			(net 308 "/PD and TB DC-DC/USB3.TX0_P")
			(pinfunction "TX_{1}+")
			(pintype "bidirectional")
		)
		(pad "A3" smd rect
			(at -1.625 -3.817)
			(size 0.27 0.9)
			(layers "F.Cu" "F.Mask" "F.Paste")
			(net 311 "/PD and TB DC-DC/USB3.TX0_N")
			(pinfunction "TX_{1}-")
			(pintype "bidirectional")
		)
		(pad "A4" smd rect
			(at -1.125 -3.817)
			(size 0.27 0.9)
			(layers "F.Cu" "F.Mask" "F.Paste")
			(net 215 "/USB-C connector/VBUS")
			(pinfunction "VBUS")
			(pintype "power_in")
		)
		(pad "A5" smd rect
			(at -0.625 -3.817)
			(size 0.27 0.9)
			(layers "F.Cu" "F.Mask" "F.Paste")
			(net 306 "/PD and TB DC-DC/USB3.CC1")
			(pinfunction "CC_{1}")
			(pintype "bidirectional")
		)
		(pad "A6" smd rect
			(at -0.125 -3.817)
			(size 0.27 0.9)
			(layers "F.Cu" "F.Mask" "F.Paste")
			(net 368 "/PD and TB DC-DC/USB3.D_A_P")
			(pinfunction "D_{A}+")
			(pintype "bidirectional")
		)
		(pad "A7" smd rect
			(at 0.374 -3.817)
			(size 0.27 0.9)
			(layers "F.Cu" "F.Mask" "F.Paste")
			(net 366 "/PD and TB DC-DC/USB3.D_A_N")
			(pinfunction "D_{A}-")
			(pintype "bidirectional")
		)
		(pad "A8" smd rect
			(at 0.874 -3.817)
			(size 0.27 0.9)
			(layers "F.Cu" "F.Mask" "F.Paste")
			(net 369 "/PD and TB DC-DC/USB3.SBU1")
			(pinfunction "SBU_{1}")
			(pintype "bidirectional")
		)
		(pad "A9" smd rect
			(at 1.374 -3.817)
			(size 0.27 0.9)
			(layers "F.Cu" "F.Mask" "F.Paste")
			(net 215 "/USB-C connector/VBUS")
			(pinfunction "VBUS")
			(pintype "passive")
		)
		(pad "A10" smd rect
			(at 1.874 -3.817)
			(size 0.27 0.9)
			(layers "F.Cu" "F.Mask" "F.Paste")
			(net 364 "/PD and TB DC-DC/USB3.RX1_N")
			(pinfunction "RX_{2}-")
			(pintype "bidirectional")
		)
		(pad "A11" smd rect
			(at 2.374 -3.817)
			(size 0.27 0.9)
			(layers "F.Cu" "F.Mask" "F.Paste")
			(net 362 "/PD and TB DC-DC/USB3.RX1_P")
			(pinfunction "RX_{2}+")
			(pintype "bidirectional")
		)
		(pad "A12" smd rect
			(at 2.874 -3.817)
			(size 0.27 0.9)
			(layers "F.Cu" "F.Mask" "F.Paste")
			(net 23 "GND")
			(pinfunction "GND")
			(pintype "passive")
		)
		(pad "B1" smd rect
			(at 2.624 -2.215)
			(size 0.27 0.8)
			(layers "F.Cu" "F.Mask" "F.Paste")
			(net 23 "GND")
			(pinfunction "GND")
			(pintype "passive")
		)
		(pad "B2" smd rect
			(at 2.124 -2.215)
			(size 0.27 0.8)
			(layers "F.Cu" "F.Mask" "F.Paste")
			(net 309 "/PD and TB DC-DC/USB3.TX1_P")
			(pinfunction "TX_{2}+")
			(pintype "bidirectional")
		)
		(pad "B3" smd rect
			(at 1.624 -2.215)
			(size 0.27 0.8)
			(layers "F.Cu" "F.Mask" "F.Paste")
			(net 312 "/PD and TB DC-DC/USB3.TX1_N")
			(pinfunction "TX_{2}-")
			(pintype "bidirectional")
		)
		(pad "B4" smd rect
			(at 1.124 -2.215)
			(size 0.27 0.8)
			(layers "F.Cu" "F.Mask" "F.Paste")
			(net 215 "/USB-C connector/VBUS")
			(pinfunction "VBUS")
			(pintype "passive")
		)
		(pad "B5" smd rect
			(at 0.624 -2.215)
			(size 0.27 0.8)
			(layers "F.Cu" "F.Mask" "F.Paste")
			(net 305 "/PD and TB DC-DC/USB3.CC2")
			(pinfunction "CC_{2}")
			(pintype "bidirectional")
		)
		(pad "B6" smd rect
			(at 0.124 -2.215)
			(size 0.27 0.8)
			(layers "F.Cu" "F.Mask" "F.Paste")
			(net 365 "/PD and TB DC-DC/USB3.D_B_P")
			(pinfunction "D_{B}+")
			(pintype "bidirectional")
		)
		(pad "B7" smd rect
			(at -0.375 -2.215)
			(size 0.27 0.8)
			(layers "F.Cu" "F.Mask" "F.Paste")
			(net 367 "/PD and TB DC-DC/USB3.D_B_N")
			(pinfunction "D_{B}-")
			(pintype "bidirectional")
		)
		(pad "B8" smd rect
			(at -0.875 -2.215)
			(size 0.27 0.8)
			(layers "F.Cu" "F.Mask" "F.Paste")
			(net 361 "/PD and TB DC-DC/USB3.SBU2")
			(pinfunction "SBU_{2}")
			(pintype "bidirectional")
		)
		(pad "B9" smd rect
			(at -1.375 -2.215)
			(size 0.27 0.8)
			(layers "F.Cu" "F.Mask" "F.Paste")
			(net 215 "/USB-C connector/VBUS")
			(pinfunction "VBUS")
			(pintype "passive")
		)
		(pad "B10" smd rect
			(at -1.875 -2.215)
			(size 0.27 0.8)
			(layers "F.Cu" "F.Mask" "F.Paste")
			(net 363 "/PD and TB DC-DC/USB3.RX0_N")
			(pinfunction "RX_{1}-")
			(pintype "bidirectional")
		)
		(pad "B11" smd rect
			(at -2.375 -2.215)
			(size 0.27 0.8)
			(layers "F.Cu" "F.Mask" "F.Paste")
			(net 360 "/PD and TB DC-DC/USB3.RX0_P")
			(pinfunction "RX_{1}+")
			(pintype "bidirectional")
		)
		(pad "B12" smd rect
			(at -2.875 -2.215)
			(size 0.27 0.8)
			(layers "F.Cu" "F.Mask" "F.Paste")
			(net 23 "GND")
			(pinfunction "GND")
			(pintype "passive")
		)
		(pad "SH" thru_hole oval
			(at -4.321 1.933)
			(size 1.3 2.6)
			(drill oval 0.75 2.05)
			(layers "*.Cu" "*.Mask")
			(remove_unused_layers no)
			(net 23 "GND")
			(pinfunction "SH")
			(pintype "passive")
		)
		(pad "SH" thru_hole custom
			(at -4.32 -3.12)
			(size 1.2 1.2)
			(drill oval 0.6 1.9)
			(layers "*.Cu" "*.Mask")
			(remove_unused_layers no)
			(net 23 "GND")
			(pinfunction "SH")
			(pintype "passive")
			(thermal_bridge_angle 90)
			(options
				(clearance outline)
				(anchor circle)
			)
			(primitives
				(gr_line
					(start 0.6 0.6)
					(end 0 0.6)
					(width 1.1)
				)
				(gr_line
					(start 0 -0.55)
					(end 0 0.55)
					(width 1.2)
				)
			)
		)
		(pad "SH" thru_hole oval
			(at -3.99 -2.52 90)
			(size 1 1.55)
			(drill oval 0.7 1.25)
			(layers "*.Cu" "*.Mask")
			(remove_unused_layers no)
			(net 23 "GND")
			(pinfunction "SH")
			(pintype "passive")
		)
		(pad "SH" thru_hole oval
			(at 3.99 -2.52 270)
			(size 1 1.55)
			(drill oval 0.7 1.25)
			(layers "*.Cu" "*.Mask")
			(remove_unused_layers no)
			(net 23 "GND")
			(pinfunction "SH")
			(pintype "passive")
		)
		(pad "SH" thru_hole custom
			(at 4.32 -3.12)
			(size 1.2 1.2)
			(drill oval 0.6 1.9)
			(layers "*.Cu" "*.Mask")
			(remove_unused_layers no)
			(net 23 "GND")
			(pinfunction "SH")
			(pintype "passive")
			(thermal_bridge_angle 90)
			(options
				(clearance outline)
				(anchor circle)
			)
			(primitives
				(gr_line
					(start -0.6 0.6)
					(end 0 0.6)
					(width 1.1)
				)
				(gr_line
					(start 0 -0.55)
					(end 0 0.55)
					(width 1.2)
				)
			)
		)
		(pad "SH" thru_hole oval
			(at 4.32 1.933)
			(size 1.3 2.6)
			(drill oval 0.75 2.05)
			(layers "*.Cu" "*.Mask")
			(remove_unused_layers no)
			(net 23 "GND")
			(pinfunction "SH")
			(pintype "passive")
		)
		(zone
			(net 0)
			(net_name "")
			(layer "F.Cu")
			(name "TOP_KEEPOUT")
			(hatch full 0.508)
			(connect_pads
				(clearance 0)
			)
			(min_thickness 0.01)
			(filled_areas_thickness no)
			(keepout
				(tracks not_allowed)
				(vias not_allowed)
				(pads not_allowed)
				(copperpour not_allowed)
				(footprints allowed)
			)
			(placement
				(enabled no)
				(sheetname "")
			)
			(fill
				(thermal_gap 0.508)
				(thermal_bridge_width 0.508)
			)
			(polygon
				(pts
					(xy 126.274008 150.484992) (xy 125.474736 150.485073) (xy 125.473728 149.799081) (xy 119.135 149.799)
					(xy 119.135 150.565) (xy 118.475 150.565) (xy 118.475 151.948) (xy 118.824 151.948) (xy 118.824 154.548)
					(xy 118.475 154.548) (xy 118.475 155.048) (xy 126.274 155.048) (xy 126.274 154.548) (xy 125.925 154.548)
					(xy 125.925 151.948) (xy 126.274 151.948)
				)
			)
		)
	)
)
